(kicad_pcb
	(version 20221018)
	(generator pcbnew)
	(general
    (thickness 1.62)
  )
	(paper "A4")
	(title_block
    (title "ECP5 - Datacenter Secure Control Module (DC-SCM)")
    (date "2024-07-01")
    (rev "1.2.1")
		(comment 9 "footprints 111-117 of 506")
	)
	(layers
    (0 "F.Cu" signal)
    (1 "In1.Cu" power)
    (2 "In2.Cu" signal)
    (3 "In3.Cu" power)
    (4 "In4.Cu" power)
    (5 "In5.Cu" signal)
    (6 "In6.Cu" power)
    (31 "B.Cu" signal)
    (32 "B.Adhes" user "B.Adhesive")
    (33 "F.Adhes" user "F.Adhesive")
    (34 "B.Paste" user)
    (35 "F.Paste" user)
    (36 "B.SilkS" user "B.Silkscreen")
    (37 "F.SilkS" user "F.Silkscreen")
    (38 "B.Mask" user)
    (39 "F.Mask" user)
    (40 "Dwgs.User" user "User.Drawings")
    (41 "Cmts.User" user "User.Comments")
    (42 "Eco1.User" user "User.Eco1")
    (43 "Eco2.User" user "User.Eco2")
    (44 "Edge.Cuts" user)
    (45 "Margin" user)
    (46 "B.CrtYd" user "B.Courtyard")
    (47 "F.CrtYd" user "F.Courtyard")
    (48 "B.Fab" user)
    (49 "F.Fab" user)
  )
	(footprint "antmicro-footprints:R_0402_1005Metric" (layer "F.Cu")
    (at 79.24 73.64 -90)
    (descr "Resistor SMD 0402")
    (tags "resistor SMD 0402")
    (property "Author" "Antmicro")
    (property "License" "Apache-2.0")
    (property "MPN" "CR0402-FX-1003GLF")
    (property "Manufacturer" "Bourns")
    (property "Public" "False")
    (property "Sheetfile" "power-supply.kicad_sch")
    (property "Sheetname" "Power supply")
    (property "Tolerance" "1%")
    (property "Val" "100k")
    (property "ki_description" "SMD Chip Resistor, 100 kohm, ± 1%, 62.5 mW, 0402 [1005 Metric], Thick Film, General Purpose")
    (property "ki_keywords" "0402, SMT, RESISTOR, PASSIVE")
    (attr smd)
    (fp_text reference "R85" (at -2.45 4.8 -90) (layer "F.SilkS")
        (effects (font (size 0.7 0.7) (thickness 0.127)))
    )
    (fp_text value "R_100k_0402" (at 0 1.17 -90) (layer "F.Fab")
        (effects (font (size 1 1) (thickness 0.15)))
    )
    (fp_text user "Author: Antmicro" (at -0.95 4.169 -90) (layer "F.Fab") hide
        (effects (font (size 0.7 0.7) (thickness 0.15)) (justify left bottom))
    )
    (fp_text user "License: Apache-2.0" (at -0.95 5.169 -90) (layer "F.Fab") hide
        (effects (font (size 0.7 0.7) (thickness 0.15)) (justify left bottom))
    )
    (fp_text user "${REFERENCE}" (at 0 0 -90) (layer "F.Fab")
        (effects (font (size 0.25 0.25) (thickness 0.04)))
    )
    (fp_rect (start -0.925 -0.47) (end 0.925 0.47)
      (stroke (width 0.05) (type default)) (fill none) (layer "F.CrtYd"))
    (fp_rect (start -0.5 -0.25) (end 0.5 0.25)
      (stroke (width 0.15) (type solid)) (fill none) (layer "F.Fab"))
    (pad "1" smd roundrect (at -0.48 0 270) (size 0.59 0.64) (layers "F.Cu" "F.Paste" "F.Mask") (roundrect_rratio 0.25)
      (net 11 "VCC5V0") (pintype "passive"))
    (pad "2" smd roundrect (at 0.48 0 270) (size 0.59 0.64) (layers "F.Cu" "F.Paste" "F.Mask") (roundrect_rratio 0.25)
      (net 419 "Net-(U12-FLAG1)") (pintype "passive"))
  )
	(footprint "antmicro-footprints:PowerDI5" (layer "F.Cu")
    (at 69.25 61 180)
    (property "Author" "Antmicro")
    (property "License" "Apache-2.0")
    (property "MPN" "PDS760-13")
    (property "Manufacturer" "Diodes Incorporated")
    (property "Sheetfile" "power-supply.kicad_sch")
    (property "Sheetname" "Power supply")
    (property "ki_description" "Schottky Rectifier, POWERDI®, 60 V, 7 A, Single, PowerDI 5, 2 Pins, 620 mV")
    (property "ki_keywords" "SMT, RECTIFIER, SEMICONDUCTOR, DIODE, SCHOTTKY")
    (attr smd)
    (fp_text reference "D6" (at 0.51 -2.975 180) (layer "F.SilkS")
        (effects (font (size 0.7 0.7) (thickness 0.15)) (justify left bottom))
    )
    (fp_text value "PDS760" (at 0 3.4) (layer "F.Fab")
        (effects (font (size 0.7 0.7) (thickness 0.15)) (justify left bottom))
    )
    (fp_text user "Author: Antmicro" (at -3.32 5.701 180) (layer "F.Fab") hide
        (effects (font (size 0.7 0.7) (thickness 0.15)) (justify left bottom))
    )
    (fp_text user "License: Apache-2.0" (at -3.32 6.901 180) (layer "F.Fab") hide
        (effects (font (size 0.7 0.7) (thickness 0.15)) (justify left bottom))
    )
    (fp_text user "${REFERENCE}" (at -3.32 4.5 180) (layer "F.Fab") hide
        (effects (font (size 0.7 0.7) (thickness 0.15)) (justify left bottom))
    )
    (fp_line (start -2.7 -2) (end 2.7 -2)
      (stroke (width 0.12) (type solid)) (layer "F.SilkS"))
    (fp_line (start -2.7 -1.8) (end -2.7 -2)
      (stroke (width 0.12) (type solid)) (layer "F.SilkS"))
    (fp_line (start -2.7 2.023) (end -2.7 1.823)
      (stroke (width 0.12) (type solid)) (layer "F.SilkS"))
    (fp_line (start 2.7 -2) (end 2.7 -1.8)
      (stroke (width 0.12) (type solid)) (layer "F.SilkS"))
    (fp_line (start 2.7 1.823) (end 2.7 2.023)
      (stroke (width 0.12) (type solid)) (layer "F.SilkS"))
    (fp_line (start 2.7 2.023) (end -2.7 2.023)
      (stroke (width 0.12) (type solid)) (layer "F.SilkS"))
    (fp_rect (start -3.702 -2.3) (end 3.7 2.3)
      (stroke (width 0.05) (type solid)) (fill none) (layer "F.CrtYd"))
    (pad "1" smd roundrect (at 1.1 0 90) (size 3.36 4.86) (layers "F.Cu" "F.Paste" "F.Mask") (roundrect_rratio 0.05)
      (net 265 "Net-(D6-C)") (pinfunction "C") (pintype "passive"))
    (pad "2" smd roundrect (at -2.862 -0.94 270) (size 1.39 1.4) (layers "F.Cu" "F.Paste" "F.Mask") (roundrect_rratio 0.25)
      (net 1 "GND") (pinfunction "A") (pintype "passive"))
    (pad "2" smd roundrect (at -2.862 0.941 90) (size 1.39 1.4) (layers "F.Cu" "F.Paste" "F.Mask") (roundrect_rratio 0.25)
      (net 1 "GND") (pinfunction "A") (pintype "passive"))
  )
	(footprint "antmicro-footprints:R_0402_1005Metric" (layer "F.Cu")
    (at 72.65 88.7)
    (descr "Resistor SMD 0402")
    (tags "resistor SMD 0402")
    (property "Author" "Antmicro")
    (property "License" "Apache-2.0")
    (property "MPN" "CR0402-FX-6652GLF")
    (property "Manufacturer" "Bourns")
    (property "Public" "False")
    (property "Sheetfile" "power-supply.kicad_sch")
    (property "Sheetname" "Power supply")
    (property "Tolerance" "1%")
    (property "Val" "66k5")
    (property "ki_description" "SMD Chip Resistor")
    (property "ki_keywords" "0402, SMT, RESISTOR, PASSIVE")
    (attr smd)
    (fp_text reference "R120" (at -0.31 1.845) (layer "F.SilkS")
        (effects (font (size 0.7 0.7) (thickness 0.127)))
    )
    (fp_text value "R_66k5_0402" (at 0 1.17) (layer "F.Fab")
        (effects (font (size 1 1) (thickness 0.15)))
    )
    (fp_text user "License: Apache-2.0" (at -0.95 5.169) (layer "F.Fab") hide
        (effects (font (size 0.7 0.7) (thickness 0.15)) (justify left bottom))
    )
    (fp_text user "${REFERENCE}" (at 0 0) (layer "F.Fab")
        (effects (font (size 0.25 0.25) (thickness 0.04)))
    )
    (fp_text user "Author: Antmicro" (at -0.95 4.169) (layer "F.Fab") hide
        (effects (font (size 0.7 0.7) (thickness 0.15)) (justify left bottom))
    )
    (fp_rect (start -0.925 -0.47) (end 0.925 0.47)
      (stroke (width 0.05) (type default)) (fill none) (layer "F.CrtYd"))
    (fp_rect (start -0.5 -0.25) (end 0.5 0.25)
      (stroke (width 0.15) (type solid)) (fill none) (layer "F.Fab"))
    (pad "1" smd roundrect (at -0.48 0) (size 0.59 0.64) (layers "F.Cu" "F.Paste" "F.Mask") (roundrect_rratio 0.25)
      (net 300 "Net-(U20-FB)") (pintype "passive"))
    (pad "2" smd roundrect (at 0.48 0) (size 0.59 0.64) (layers "F.Cu" "F.Paste" "F.Mask") (roundrect_rratio 0.25)
      (net 358 "Net-(C121-Pad2)") (pintype "passive"))
  )
	(footprint "antmicro-footprints:R_0603_1608Metric" (layer "F.Cu")
    (at 121.489056 84.693104 90)
    (descr "Resistor SMD 0603")
    (tags "resistor SMD 0603")
    (property "Author" "Antmicro")
    (property "Current" "1A")
    (property "License" "Apache-2.0")
    (property "MPN" "CR0603-J/-000ELF")
    (property "Manufacturer" "Bourns")
    (property "Public" "False")
    (property "Sheetfile" "power-supply.kicad_sch")
    (property "Sheetname" "Power supply")
    (property "Tolerance" "")
    (property "Val" "0R")
    (property "ki_description" "Zero Ohm Resistor, Jumper, 0603 [1608 Metric], Thick Film, 100 mW, 1 A, Surface Mount Device, CR")
    (property "ki_keywords" "0603, SMT, RESISTOR, PASSIVE")
    (attr smd)
    (fp_text reference "R142" (at -0.246896 1.080944 90) (layer "F.SilkS")
        (effects (font (size 0.7 0.7) (thickness 0.127)))
    )
    (fp_text value "R_0R_0603" (at 0 1.9 90) (layer "F.Fab")
        (effects (font (size 1 1) (thickness 0.15)))
    )
    (fp_text user "${REFERENCE}" (at -1.25 3.898 90) (layer "F.Fab") hide
        (effects (font (size 0.7 0.7) (thickness 0.15)) (justify left bottom))
    )
    (fp_text user "License: Apache-2.0" (at -1.25 5.9 90) (layer "F.Fab") hide
        (effects (font (size 0.7 0.7) (thickness 0.15)) (justify left bottom))
    )
    (fp_text user "Author: Antmicro" (at -1.25 4.9 90) (layer "F.Fab") hide
        (effects (font (size 0.7 0.7) (thickness 0.15)) (justify left bottom))
    )
    (fp_line (start -0.15 -0.4) (end 0.15 -0.4)
      (stroke (width 0.15) (type solid)) (layer "F.SilkS"))
    (fp_line (start -0.15 0.4) (end 0.15 0.4)
      (stroke (width 0.15) (type solid)) (layer "F.SilkS"))
    (fp_rect (start -1.25 -0.65) (end 1.25 0.65)
      (stroke (width 0.05) (type solid)) (fill none) (layer "F.CrtYd"))
    (fp_rect (start -0.8 -0.4) (end 0.8 0.4)
      (stroke (width 0.15) (type solid)) (fill none) (layer "F.Fab"))
    (pad "1" smd roundrect (at -0.7 0 90) (size 0.8 1) (layers "F.Cu" "F.Paste" "F.Mask") (roundrect_rratio 0.2)
      (net 218 "VCC1V8") (pintype "passive"))
    (pad "2" smd roundrect (at 0.7 0 90) (size 0.8 1) (layers "F.Cu" "F.Paste" "F.Mask") (roundrect_rratio 0.2)
      (net 356 "Net-(C119-Pad2)") (pintype "passive"))
  )
	(footprint "antmicro-footprints:L_Vishay-IHLP-1212AE" (layer "F.Cu")
    (at 79.25 81.55)
    (property "Author" "Antmicro")
    (property "IMax" "6.7 A")
    (property "ISat" "6.7 A")
    (property "License" "Apache-2.0")
    (property "MPN" "IHLP1212AEERR47M11")
    (property "Manufacturer" "Vishay")
    (property "Public" "False")
    (property "Sheetfile" "power-supply.kicad_sch")
    (property "Sheetname" "Power supply")
    (property "Size" "3.0x3.0")
    (property "Val" "470n/6.7A")
    (property "ki_description" "Power Inductor (SMT), 470 nH, 6.7 A, Shielded, 6.7 A")
    (property "ki_keywords" "SMT, INDUCTOR, PASSIVE")
    (attr smd)
    (fp_text reference "L5" (at -2.49 -1.295) (layer "F.SilkS")
        (effects (font (size 0.7 0.7) (thickness 0.127)))
    )
    (fp_text value "IHLP1212AEERR47M11" (at 0 0 270) (layer "F.SilkS") hide
        (effects (font (size 1.524 1.524) (thickness 0.05)))
    )
    (fp_text user "${REFERENCE}" (at -2.35 5.4) (layer "F.Fab") hide
        (effects (font (size 0.7 0.7) (thickness 0.15)) (justify left bottom))
    )
    (fp_text user "License: Apache-2.0" (at -2.35 7.8) (layer "F.Fab") hide
        (effects (font (size 0.7 0.7) (thickness 0.15)) (justify left bottom))
    )
    (fp_text user "Author: Antmicro" (at -2.35 6.6) (layer "F.Fab") hide
        (effects (font (size 0.7 0.7) (thickness 0.15)) (justify left bottom))
    )
    (fp_line (start -1.647 -1.6) (end 1.653 -1.6)
      (stroke (width 0.15) (type solid)) (layer "F.SilkS"))
    (fp_line (start -1.647 -0.9) (end -1.647 -1.6)
      (stroke (width 0.15) (type solid)) (layer "F.SilkS"))
    (fp_line (start -1.647 1.6) (end -1.647 0.9)
      (stroke (width 0.15) (type solid)) (layer "F.SilkS"))
    (fp_line (start 1.653 -1.6) (end 1.653 -0.9)
      (stroke (width 0.15) (type solid)) (layer "F.SilkS"))
    (fp_line (start 1.653 0.9) (end 1.653 1.601)
      (stroke (width 0.15) (type solid)) (layer "F.SilkS"))
    (fp_line (start 1.653 1.601) (end -1.647 1.6)
      (stroke (width 0.15) (type solid)) (layer "F.SilkS"))
    (fp_rect (start -2.35 -1.85) (end 2.35 1.85)
      (stroke (width 0.05) (type solid)) (fill none) (layer "F.CrtYd"))
    (fp_rect (start -1.803 -1.601) (end 1.803 1.601)
      (stroke (width 0.15) (type solid)) (fill none) (layer "F.Fab"))
    (pad "1" smd roundrect (at -1.35 0) (size 1.5 1.2) (layers "F.Cu" "F.Paste" "F.Mask") (roundrect_rratio 0.1)
      (net 391 "Net-(U19-SW)") (pintype "passive"))
    (pad "2" smd roundrect (at 1.35 0) (size 1.5 1.2) (layers "F.Cu" "F.Paste" "F.Mask") (roundrect_rratio 0.1)
      (net 357 "Net-(C120-Pad2)") (pintype "passive"))
  )
	(footprint "antmicro-footprints:L_Vishay-IHLP-1212AE" (layer "F.Cu")
    (at 73.2 81.55)
    (property "Author" "Antmicro")
    (property "IMax" "6.7 A")
    (property "ISat" "6.7 A")
    (property "License" "Apache-2.0")
    (property "MPN" "IHLP1212AEERR47M11")
    (property "Manufacturer" "Vishay")
    (property "Public" "False")
    (property "Sheetfile" "power-supply.kicad_sch")
    (property "Sheetname" "Power supply")
    (property "Size" "3.0x3.0")
    (property "Val" "470n/6.7A")
    (property "ki_description" "Power Inductor (SMT), 470 nH, 6.7 A, Shielded, 6.7 A")
    (property "ki_keywords" "SMT, INDUCTOR, PASSIVE")
    (attr smd)
    (fp_text reference "L6" (at -2.75 0 180) (layer "F.SilkS")
        (effects (font (size 0.7 0.7) (thickness 0.127)))
    )
    (fp_text value "IHLP1212AEERR47M11" (at 0 0 270) (layer "F.SilkS") hide
        (effects (font (size 1.524 1.524) (thickness 0.05)))
    )
    (fp_text user "${REFERENCE}" (at -2.35 5.4) (layer "F.Fab") hide
        (effects (font (size 0.7 0.7) (thickness 0.15)) (justify left bottom))
    )
    (fp_text user "Author: Antmicro" (at -2.35 6.6) (layer "F.Fab") hide
        (effects (font (size 0.7 0.7) (thickness 0.15)) (justify left bottom))
    )
    (fp_text user "License: Apache-2.0" (at -2.35 7.8) (layer "F.Fab") hide
        (effects (font (size 0.7 0.7) (thickness 0.15)) (justify left bottom))
    )
    (fp_line (start -1.647 -1.6) (end 1.653 -1.6)
      (stroke (width 0.15) (type solid)) (layer "F.SilkS"))
    (fp_line (start -1.647 -0.9) (end -1.647 -1.6)
      (stroke (width 0.15) (type solid)) (layer "F.SilkS"))
    (fp_line (start -1.647 1.6) (end -1.647 0.9)
      (stroke (width 0.15) (type solid)) (layer "F.SilkS"))
    (fp_line (start 1.653 -1.6) (end 1.653 -0.9)
      (stroke (width 0.15) (type solid)) (layer "F.SilkS"))
    (fp_line (start 1.653 0.9) (end 1.653 1.601)
      (stroke (width 0.15) (type solid)) (layer "F.SilkS"))
    (fp_line (start 1.653 1.601) (end -1.647 1.6)
      (stroke (width 0.15) (type solid)) (layer "F.SilkS"))
    (fp_rect (start -2.35 -1.85) (end 2.35 1.85)
      (stroke (width 0.05) (type solid)) (fill none) (layer "F.CrtYd"))
    (fp_rect (start -1.803 -1.601) (end 1.803 1.601)
      (stroke (width 0.15) (type solid)) (fill none) (layer "F.Fab"))
    (pad "1" smd roundrect (at -1.35 0) (size 1.5 1.2) (layers "F.Cu" "F.Paste" "F.Mask") (roundrect_rratio 0.1)
      (net 392 "Net-(U20-SW)") (pintype "passive"))
    (pad "2" smd roundrect (at 1.35 0) (size 1.5 1.2) (layers "F.Cu" "F.Paste" "F.Mask") (roundrect_rratio 0.1)
      (net 358 "Net-(C121-Pad2)") (pintype "passive"))
  )
	(footprint "antmicro-footprints:QFN-8_2x1.5mm" (layer "F.Cu")
    (at 117.989056 83.643104 90)
    (property "Author" "Antmicro")
    (property "License" "Apache-2.0")
    (property "MPN" "TPS62823DLCT")
    (property "Manufacturer" "Texas Instruments")
    (property "Sheetfile" "power-supply.kicad_sch")
    (property "Sheetname" "Power supply")
    (property "ki_description" "DC/DC converter")
    (property "ki_keywords" "SMT, PMIC, IC, SWITCHING, VOLTAGE, REGULATOR, DC-DC")
    (attr smd)
    (fp_text reference "U18" (at -0.05 -2.48 90) (layer "F.SilkS")
        (effects (font (size 0.7 0.7) (thickness 0.127)))
    )
    (fp_text value "TPS62823DLCT" (at 0 2.075 90) (layer "F.Fab")
        (effects (font (size 1 1) (thickness 0.15)))
    )
    (fp_text user "License: Apache-2.0" (at -1.651 6.475 90) (layer "F.Fab") hide
        (effects (font (size 0.7 0.7) (thickness 0.15)) (justify left bottom))
    )
    (fp_text user "Author: Antmicro" (at -1.651 5.275 90) (layer "F.Fab") hide
        (effects (font (size 0.7 0.7) (thickness 0.15)) (justify left bottom))
    )
    (fp_text user "${REFERENCE}" (at 0 0 90) (layer "F.Fab")
        (effects (font (size 0.5 0.5) (thickness 0.075)))
    )
    (fp_line (start -0.9 1.05) (end 0.9 1.05)
      (stroke (width 0.15) (type solid)) (layer "F.SilkS"))
    (fp_line (start -0.25 -1.05) (end 0.9 -1.05)
      (stroke (width 0.15) (type solid)) (layer "F.SilkS"))
    (fp_circle (center -0.9 -1.05) (end -0.849 -1.05)
      (stroke (width 0.15) (type solid)) (fill solid) (layer "F.SilkS"))
    (fp_rect (start -1.1 -1.25) (end 1.1 1.25)
      (stroke (width 0.05) (type solid)) (fill none) (layer "F.CrtYd"))
    (fp_line (start -1 -0.5) (end -0.5 -1)
      (stroke (width 0.15) (type solid)) (layer "F.Fab"))
    (fp_line (start -1 0.998) (end -1 -0.5)
      (stroke (width 0.15) (type solid)) (layer "F.Fab"))
    (fp_line (start -0.5 -1) (end 0.998 -1)
      (stroke (width 0.15) (type solid)) (layer "F.Fab"))
    (fp_line (start 0.998 -1) (end 0.998 0.998)
      (stroke (width 0.15) (type solid)) (layer "F.Fab"))
    (fp_line (start 0.998 0.998) (end -1 0.998)
      (stroke (width 0.15) (type solid)) (layer "F.Fab"))
    (pad "1" smd rect (at -0.677 -0.75 90) (size 0.55 0.25) (layers "F.Cu" "F.Paste" "F.Mask")
      (net 231 "/Power supply/VCCIO_EN") (pinfunction "EN") (pintype "input"))
    (pad "2" smd rect (at -0.677 -0.25 90) (size 0.55 0.25) (layers "F.Cu" "F.Paste" "F.Mask")
      (net 292 "Net-(U18-FB)") (pinfunction "FB") (pintype "bidirectional"))
    (pad "3" smd rect (at -0.677 0.248 90) (size 0.55 0.25) (layers "F.Cu" "F.Paste" "F.Mask")
      (net 1 "GND") (pinfunction "AGND") (pintype "power_in"))
    (pad "4" smd rect (at -0.677 0.748 90) (size 0.55 0.25) (layers "F.Cu" "F.Paste" "F.Mask")
      (net 544 "unconnected-(U18-NC-Pad4)") (pinfunction "NC") (pintype "no_connect"))
    (pad "5" smd rect (at 0.675 0.748 90) (size 0.55 0.25) (layers "F.Cu" "F.Paste" "F.Mask")
      (net 1 "GND") (pinfunction "PGND") (pintype "power_in"))
    (pad "6" smd rect (at 0.675 0.248 90) (size 0.55 0.25) (layers "F.Cu" "F.Paste" "F.Mask")
      (net 390 "Net-(U18-SW)") (pinfunction "SW") (pintype "bidirectional"))
    (pad "7" smd rect (at 0.675 -0.25 90) (size 0.55 0.25) (layers "F.Cu" "F.Paste" "F.Mask")
      (net 11 "VCC5V0") (pinfunction "VIN") (pintype "power_in"))
    (pad "8" smd rect (at 0.675 -0.75 90) (size 0.55 0.25) (layers "F.Cu" "F.Paste" "F.Mask")
      (net 223 "/Power supply/1V8_PG") (pinfunction "PG") (pintype "output"))
  )
)
